(kicad_pcb
	(version 20260206)
	(generator "pcbnew")
	(generator_version "10.0")
	(general
		(thickness 1.6)
		(legacy_teardrops no)
	)
	(paper "A4")
	(title_block
		(title "01162023_DA0F0TEBIF0_F0T_Expander_BD_F_brd_V02_OCP.brd")
		(comment 1 "Grand Teton / footprints 3689-3696 of 9728")
	)
	(layers
		(0 "F.Cu" signal "TOP")
		(4 "In1.Cu" signal "GND")
		(6 "In2.Cu" signal "VCC")
		(8 "In3.Cu" signal "VCC1")
		(10 "In4.Cu" signal "GND1")
		(12 "In5.Cu" signal "IN1")
		(14 "In6.Cu" signal "GND2")
		(16 "In7.Cu" signal "IN2")
		(18 "In8.Cu" signal "GND3")
		(20 "In9.Cu" signal "IN3")
		(22 "In10.Cu" signal "GND4")
		(24 "In11.Cu" signal "IN4")
		(26 "In12.Cu" signal "GND5")
		(28 "In13.Cu" signal "IN5")
		(30 "In14.Cu" signal "GND6")
		(32 "In15.Cu" signal "IN6")
		(34 "In16.Cu" signal "GND7")
		(2 "B.Cu" signal "BOTTOM")
		(9 "F.Adhes" user "F.Adhesive")
		(11 "B.Adhes" user "B.Adhesive")
		(13 "F.Paste" user "Package Geometry/Pastemask Top")
		(15 "B.Paste" user "Package Geometry/Pastemask Bottom")
		(5 "F.SilkS" user "Ref Des/Silkscreen Top")
		(7 "B.SilkS" user "Ref Des/Silkscreen Bottom")
		(1 "F.Mask" user "Board Geometry/Soldermask Top")
		(3 "B.Mask" user "Board Geometry/Soldermask Bottom")
		(17 "Dwgs.User" user "User.Drawings")
		(19 "Cmts.User" user "User.Comments")
		(21 "Eco1.User" user "User.Eco1")
		(23 "Eco2.User" user "User.Eco2")
		(25 "Edge.Cuts" user "Board Geometry/Outline")
		(27 "Margin" user)
		(31 "F.CrtYd" user "Package Geometry/Place Bound Top")
		(29 "B.CrtYd" user "Package Geometry/Place Bound Bottom")
		(35 "F.Fab" user "Ref Des/Assembly Top")
		(33 "B.Fab" user "Ref Des/Assembly Bottom")
	)
	(footprint ""
		(layer "F.Cu")
		(at 34.75609 -115.590574 90)
		(property "Reference" "U9"
			(at 2.670556 -1.22809 0)
			(unlocked yes)
			(layer "F.SilkS")
			(effects
				(font
					(size 0.7874 0.5842)
					(thickness 0.1524)
				)
			)
		)
		(property "Value" ""
			(at 0 0 90)
			(layer "F.Fab")
			(effects
				(font
					(size 1.27 1.27)
				)
			)
		)
		(duplicate_pad_numbers_are_jumpers no)
		(fp_line
			(start -1.949958 -1.610106)
			(end 1.949958 -1.610106)
			(stroke
				(width 0.1524)
				(type default)
			)
			(layer "F.SilkS")
		)
		(fp_line
			(start 1.949958 -1.560068)
			(end 1.949958 1.610106)
			(stroke
				(width 0.1524)
				(type default)
			)
			(layer "F.SilkS")
		)
		(fp_line
			(start 1.949958 1.610106)
			(end -1.949958 1.610106)
			(stroke
				(width 0.1524)
				(type default)
			)
			(layer "F.SilkS")
		)
		(fp_line
			(start -1.949958 1.610106)
			(end -1.949958 -1.610106)
			(stroke
				(width 0.1524)
				(type default)
			)
			(layer "F.SilkS")
		)
		(fp_line
			(start 0.750062 -1.560068)
			(end 0.750062 1.560068)
			(stroke
				(width 0.1)
				(type default)
			)
			(layer "F.Fab")
		)
		(fp_line
			(start -0.750062 -1.560068)
			(end 0.750062 -1.560068)
			(stroke
				(width 0.1)
				(type default)
			)
			(layer "F.Fab")
		)
		(fp_line
			(start 0.750062 1.560068)
			(end -0.750062 1.560068)
			(stroke
				(width 0.1)
				(type default)
			)
			(layer "F.Fab")
		)
		(fp_line
			(start -0.750062 1.560068)
			(end -0.750062 -1.560068)
			(stroke
				(width 0.1)
				(type default)
			)
			(layer "F.Fab")
		)
		(pad "D" smd rect
			(at 1.100074 0)
			(size 1.016 1.4224)
			(layers "F.Cu" "F.Mask" "F.Paste")
			(net "HP_NIC0_EN")
		)
		(pad "G" smd rect
			(at -1.100074 -0.94996)
			(size 1.016 1.4224)
			(layers "F.Cu" "F.Mask" "F.Paste")
			(net "PRSNT_NIC0_R_N")
		)
		(pad "S" smd rect
			(at -1.100074 0.94996)
			(size 1.016 1.4224)
			(layers "F.Cu" "F.Mask" "F.Paste")
			(net "GND")
		)
	)
	(footprint ""
		(layer "F.Cu")
		(at 214.454486 -212.206586)
		(property "Reference" "R5719"
			(at 0 0 0)
			(layer "F.SilkS")
			(hide yes)
			(effects
				(font
					(size 1.27 1.27)
				)
			)
		)
		(property "Value" ""
			(at 0 0 0)
			(layer "F.Fab")
			(effects
				(font
					(size 1.27 1.27)
				)
			)
		)
		(duplicate_pad_numbers_are_jumpers no)
		(fp_line
			(start -0.7874 -0.4064)
			(end 0.7874 -0.4064)
			(stroke
				(width 0.1524)
				(type default)
			)
			(layer "F.SilkS")
		)
		(fp_line
			(start -0.7874 0.4064)
			(end -0.7874 -0.4064)
			(stroke
				(width 0.1524)
				(type default)
			)
			(layer "F.SilkS")
		)
		(fp_line
			(start 0.7874 -0.4064)
			(end 0.7874 0.4064)
			(stroke
				(width 0.1524)
				(type default)
			)
			(layer "F.SilkS")
		)
		(fp_line
			(start 0.7874 0.4064)
			(end -0.7874 0.4064)
			(stroke
				(width 0.1524)
				(type default)
			)
			(layer "F.SilkS")
		)
		(fp_line
			(start -0.67945 -0.305054)
			(end -0.12065 -0.305054)
			(stroke
				(width 0.1)
				(type default)
			)
			(layer "F.Fab")
		)
		(fp_line
			(start -0.67945 0.3048)
			(end -0.67945 -0.305054)
			(stroke
				(width 0.1)
				(type default)
			)
			(layer "F.Fab")
		)
		(fp_line
			(start -0.12065 -0.305054)
			(end -0.12065 -0.2794)
			(stroke
				(width 0.1)
				(type default)
			)
			(layer "F.Fab")
		)
		(fp_line
			(start -0.12065 -0.2794)
			(end 0.12065 -0.2794)
			(stroke
				(width 0.1)
				(type default)
			)
			(layer "F.Fab")
		)
		(fp_line
			(start -0.12065 0.2794)
			(end -0.12065 0.3048)
			(stroke
				(width 0.1)
				(type default)
			)
			(layer "F.Fab")
		)
		(fp_line
			(start -0.12065 0.3048)
			(end -0.67945 0.3048)
			(stroke
				(width 0.1)
				(type default)
			)
			(layer "F.Fab")
		)
		(fp_line
			(start 0.120396 0.2794)
			(end -0.12065 0.2794)
			(stroke
				(width 0.1)
				(type default)
			)
			(layer "F.Fab")
		)
		(fp_line
			(start 0.120396 0.3048)
			(end 0.120396 0.2794)
			(stroke
				(width 0.1)
				(type default)
			)
			(layer "F.Fab")
		)
		(fp_line
			(start 0.12065 -0.3048)
			(end 0.67945 -0.3048)
			(stroke
				(width 0.1)
				(type default)
			)
			(layer "F.Fab")
		)
		(fp_line
			(start 0.12065 -0.2794)
			(end 0.12065 -0.3048)
			(stroke
				(width 0.1)
				(type default)
			)
			(layer "F.Fab")
		)
		(fp_line
			(start 0.67945 -0.3048)
			(end 0.67945 0.3048)
			(stroke
				(width 0.1)
				(type default)
			)
			(layer "F.Fab")
		)
		(fp_line
			(start 0.67945 0.3048)
			(end 0.120396 0.3048)
			(stroke
				(width 0.1)
				(type default)
			)
			(layer "F.Fab")
		)
		(pad "1" smd circle
			(at -0.40005 0)
			(size 0 0)
			(layers "F.Cu" "F.Mask" "F.Paste")
			(net "RST_BIC_I2C9_SSD_MUX1_R_N")
		)
		(pad "2" smd circle
			(at 0.40005 0)
			(size 0 0)
			(layers "F.Cu" "F.Mask" "F.Paste")
			(net "RST_BIC_I2C9_SSD_MUX1_N")
		)
	)
	(footprint ""
		(layer "F.Cu")
		(at 18.451322 -114.914426 -90)
		(property "Reference" "PC661"
			(at 0 0 270)
			(layer "F.SilkS")
			(hide yes)
			(effects
				(font
					(size 1.27 1.27)
				)
			)
		)
		(property "Value" ""
			(at 0 0 270)
			(layer "F.Fab")
			(effects
				(font
					(size 1.27 1.27)
				)
			)
		)
		(duplicate_pad_numbers_are_jumpers no)
		(fp_line
			(start -1.524 0.762)
			(end -1.524 -0.762)
			(stroke
				(width 0.1524)
				(type default)
			)
			(layer "F.SilkS")
		)
		(fp_line
			(start 1.524 0.762)
			(end -1.524 0.762)
			(stroke
				(width 0.1524)
				(type default)
			)
			(layer "F.SilkS")
		)
		(fp_line
			(start -1.524 -0.762)
			(end 1.524 -0.762)
			(stroke
				(width 0.1524)
				(type default)
			)
			(layer "F.SilkS")
		)
		(fp_line
			(start 1.524 -0.762)
			(end 1.524 0.762)
			(stroke
				(width 0.1524)
				(type default)
			)
			(layer "F.SilkS")
		)
		(fp_line
			(start -1.1049 0.724916)
			(end 1.1049 0.724916)
			(stroke
				(width 0.1)
				(type default)
			)
			(layer "F.Fab")
		)
		(fp_line
			(start 1.1049 0.724916)
			(end 1.1049 -0.724916)
			(stroke
				(width 0.1)
				(type default)
			)
			(layer "F.Fab")
		)
		(fp_line
			(start -1.1049 -0.724916)
			(end -1.1049 0.724916)
			(stroke
				(width 0.1)
				(type default)
			)
			(layer "F.Fab")
		)
		(fp_line
			(start 1.1049 -0.724916)
			(end -1.1049 -0.724916)
			(stroke
				(width 0.1)
				(type default)
			)
			(layer "F.Fab")
		)
		(pad "1" smd rect
			(at -0.889 0 90)
			(size 1.016 1.27)
			(layers "F.Cu" "F.Mask" "F.Paste")
			(net "P3V3_NIC0")
		)
		(pad "2" smd rect
			(at 0.889 0 90)
			(size 1.016 1.27)
			(layers "F.Cu" "F.Mask" "F.Paste")
			(net "GND")
		)
	)
	(footprint ""
		(layer "F.Cu")
		(at 87.132922 -343.952322 90)
		(property "Reference" "C152"
			(at 0 0 90)
			(layer "F.SilkS")
			(hide yes)
			(effects
				(font
					(size 1.27 1.27)
				)
			)
		)
		(property "Value" ""
			(at 0 0 90)
			(layer "F.Fab")
			(effects
				(font
					(size 1.27 1.27)
				)
			)
		)
		(duplicate_pad_numbers_are_jumpers no)
		(fp_line
			(start 0.299974 -0.150114)
			(end 0.299974 0.150114)
			(stroke
				(width 0.1)
				(type default)
			)
			(layer "F.Fab")
		)
		(fp_line
			(start -0.299974 -0.150114)
			(end 0.299974 -0.150114)
			(stroke
				(width 0.1)
				(type default)
			)
			(layer "F.Fab")
		)
		(fp_line
			(start 0.299974 0.150114)
			(end -0.299974 0.150114)
			(stroke
				(width 0.1)
				(type default)
			)
			(layer "F.Fab")
		)
		(fp_line
			(start -0.299974 0.150114)
			(end -0.299974 -0.150114)
			(stroke
				(width 0.1)
				(type default)
			)
			(layer "F.Fab")
		)
		(pad "1" smd rect
			(at -0.2667 0 90)
			(size 0.3048 0.381)
			(layers "F.Cu" "F.Mask" "F.Paste")
			(net "P5E_PEX0_STN6_TX_DN<100>")
		)
		(pad "2" smd rect
			(at 0.2667 0 90)
			(size 0.3048 0.381)
			(layers "F.Cu" "F.Mask" "F.Paste")
			(net "P5E_PEX0_STN6_TX_C_DN<100>")
		)
	)
	(footprint ""
		(layer "F.Cu")
		(at 338.074 -160.782 180)
		(property "Reference" "R4824"
			(at 0 0 180)
			(layer "F.SilkS")
			(hide yes)
			(effects
				(font
					(size 1.27 1.27)
				)
			)
		)
		(property "Value" ""
			(at 0 0 180)
			(layer "F.Fab")
			(effects
				(font
					(size 1.27 1.27)
				)
			)
		)
		(duplicate_pad_numbers_are_jumpers no)
		(fp_line
			(start 0.7874 0.4064)
			(end -0.7874 0.4064)
			(stroke
				(width 0.1524)
				(type default)
			)
			(layer "F.SilkS")
		)
		(fp_line
			(start 0.7874 -0.4064)
			(end 0.7874 0.4064)
			(stroke
				(width 0.1524)
				(type default)
			)
			(layer "F.SilkS")
		)
		(fp_line
			(start -0.7874 0.4064)
			(end -0.7874 -0.4064)
			(stroke
				(width 0.1524)
				(type default)
			)
			(layer "F.SilkS")
		)
		(fp_line
			(start -0.7874 -0.4064)
			(end 0.7874 -0.4064)
			(stroke
				(width 0.1524)
				(type default)
			)
			(layer "F.SilkS")
		)
		(fp_line
			(start 0.67945 0.3048)
			(end 0.120396 0.3048)
			(stroke
				(width 0.1)
				(type default)
			)
			(layer "F.Fab")
		)
		(fp_line
			(start 0.67945 -0.3048)
			(end 0.67945 0.3048)
			(stroke
				(width 0.1)
				(type default)
			)
			(layer "F.Fab")
		)
		(fp_line
			(start 0.12065 -0.2794)
			(end 0.12065 -0.3048)
			(stroke
				(width 0.1)
				(type default)
			)
			(layer "F.Fab")
		)
		(fp_line
			(start 0.12065 -0.3048)
			(end 0.67945 -0.3048)
			(stroke
				(width 0.1)
				(type default)
			)
			(layer "F.Fab")
		)
		(fp_line
			(start 0.120396 0.3048)
			(end 0.120396 0.2794)
			(stroke
				(width 0.1)
				(type default)
			)
			(layer "F.Fab")
		)
		(fp_line
			(start 0.120396 0.2794)
			(end -0.12065 0.2794)
			(stroke
				(width 0.1)
				(type default)
			)
			(layer "F.Fab")
		)
		(fp_line
			(start -0.12065 0.3048)
			(end -0.67945 0.3048)
			(stroke
				(width 0.1)
				(type default)
			)
			(layer "F.Fab")
		)
		(fp_line
			(start -0.12065 0.2794)
			(end -0.12065 0.3048)
			(stroke
				(width 0.1)
				(type default)
			)
			(layer "F.Fab")
		)
		(fp_line
			(start -0.12065 -0.2794)
			(end 0.12065 -0.2794)
			(stroke
				(width 0.1)
				(type default)
			)
			(layer "F.Fab")
		)
		(fp_line
			(start -0.12065 -0.305054)
			(end -0.12065 -0.2794)
			(stroke
				(width 0.1)
				(type default)
			)
			(layer "F.Fab")
		)
		(fp_line
			(start -0.67945 0.3048)
			(end -0.67945 -0.305054)
			(stroke
				(width 0.1)
				(type default)
			)
			(layer "F.Fab")
		)
		(fp_line
			(start -0.67945 -0.305054)
			(end -0.12065 -0.305054)
			(stroke
				(width 0.1)
				(type default)
			)
			(layer "F.Fab")
		)
		(pad "1" smd circle
			(at -0.40005 0 180)
			(size 0 0)
			(layers "F.Cu" "F.Mask" "F.Paste")
			(net "GND")
		)
		(pad "2" smd circle
			(at 0.40005 0 180)
			(size 0 0)
			(layers "F.Cu" "F.Mask" "F.Paste")
			(net "PCA9555_0_PEX3_A2")
		)
	)
	(footprint ""
		(layer "F.Cu")
		(at 334.240124 -343.952322 90)
		(property "Reference" "C529"
			(at 0 0 90)
			(layer "F.SilkS")
			(hide yes)
			(effects
				(font
					(size 1.27 1.27)
				)
			)
		)
		(property "Value" ""
			(at 0 0 90)
			(layer "F.Fab")
			(effects
				(font
					(size 1.27 1.27)
				)
			)
		)
		(duplicate_pad_numbers_are_jumpers no)
		(fp_line
			(start 0.299974 -0.150114)
			(end 0.299974 0.150114)
			(stroke
				(width 0.1)
				(type default)
			)
			(layer "F.Fab")
		)
		(fp_line
			(start -0.299974 -0.150114)
			(end 0.299974 -0.150114)
			(stroke
				(width 0.1)
				(type default)
			)
			(layer "F.Fab")
		)
		(fp_line
			(start 0.299974 0.150114)
			(end -0.299974 0.150114)
			(stroke
				(width 0.1)
				(type default)
			)
			(layer "F.Fab")
		)
		(fp_line
			(start -0.299974 0.150114)
			(end -0.299974 -0.150114)
			(stroke
				(width 0.1)
				(type default)
			)
			(layer "F.Fab")
		)
		(pad "1" smd rect
			(at -0.2667 0 90)
			(size 0.3048 0.381)
			(layers "F.Cu" "F.Mask" "F.Paste")
			(net "P5E_PEX2_STN5_TX_DP<90>")
		)
		(pad "2" smd rect
			(at 0.2667 0 90)
			(size 0.3048 0.381)
			(layers "F.Cu" "F.Mask" "F.Paste")
			(net "P5E_PEX2_STN5_TX_C_DP<90>")
		)
	)
	(footprint ""
		(layer "F.Cu")
		(at 452.567802 -53.051456)
		(property "Reference" "R4473"
			(at 0 0 0)
			(layer "F.SilkS")
			(hide yes)
			(effects
				(font
					(size 1.27 1.27)
				)
			)
		)
		(property "Value" ""
			(at 0 0 0)
			(layer "F.Fab")
			(effects
				(font
					(size 1.27 1.27)
				)
			)
		)
		(duplicate_pad_numbers_are_jumpers no)
		(fp_line
			(start -0.7874 -0.4064)
			(end 0.7874 -0.4064)
			(stroke
				(width 0.1524)
				(type default)
			)
			(layer "F.SilkS")
		)
		(fp_line
			(start -0.7874 0.4064)
			(end -0.7874 -0.4064)
			(stroke
				(width 0.1524)
				(type default)
			)
			(layer "F.SilkS")
		)
		(fp_line
			(start 0.7874 -0.4064)
			(end 0.7874 0.4064)
			(stroke
				(width 0.1524)
				(type default)
			)
			(layer "F.SilkS")
		)
		(fp_line
			(start 0.7874 0.4064)
			(end -0.7874 0.4064)
			(stroke
				(width 0.1524)
				(type default)
			)
			(layer "F.SilkS")
		)
		(fp_line
			(start -0.67945 -0.305054)
			(end -0.12065 -0.305054)
			(stroke
				(width 0.1)
				(type default)
			)
			(layer "F.Fab")
		)
		(fp_line
			(start -0.67945 0.3048)
			(end -0.67945 -0.305054)
			(stroke
				(width 0.1)
				(type default)
			)
			(layer "F.Fab")
		)
		(fp_line
			(start -0.12065 -0.305054)
			(end -0.12065 -0.2794)
			(stroke
				(width 0.1)
				(type default)
			)
			(layer "F.Fab")
		)
		(fp_line
			(start -0.12065 -0.2794)
			(end 0.12065 -0.2794)
			(stroke
				(width 0.1)
				(type default)
			)
			(layer "F.Fab")
		)
		(fp_line
			(start -0.12065 0.2794)
			(end -0.12065 0.3048)
			(stroke
				(width 0.1)
				(type default)
			)
			(layer "F.Fab")
		)
		(fp_line
			(start -0.12065 0.3048)
			(end -0.67945 0.3048)
			(stroke
				(width 0.1)
				(type default)
			)
			(layer "F.Fab")
		)
		(fp_line
			(start 0.120396 0.2794)
			(end -0.12065 0.2794)
			(stroke
				(width 0.1)
				(type default)
			)
			(layer "F.Fab")
		)
		(fp_line
			(start 0.120396 0.3048)
			(end 0.120396 0.2794)
			(stroke
				(width 0.1)
				(type default)
			)
			(layer "F.Fab")
		)
		(fp_line
			(start 0.12065 -0.3048)
			(end 0.67945 -0.3048)
			(stroke
				(width 0.1)
				(type default)
			)
			(layer "F.Fab")
		)
		(fp_line
			(start 0.12065 -0.2794)
			(end 0.12065 -0.3048)
			(stroke
				(width 0.1)
				(type default)
			)
			(layer "F.Fab")
		)
		(fp_line
			(start 0.67945 -0.3048)
			(end 0.67945 0.3048)
			(stroke
				(width 0.1)
				(type default)
			)
			(layer "F.Fab")
		)
		(fp_line
			(start 0.67945 0.3048)
			(end 0.120396 0.3048)
			(stroke
				(width 0.1)
				(type default)
			)
			(layer "F.Fab")
		)
		(pad "1" smd circle
			(at -0.40005 0)
			(size 0 0)
			(layers "F.Cu" "F.Mask" "F.Paste")
			(net "PWRGD_P12V_SSD15")
		)
		(pad "2" smd circle
			(at 0.40005 0)
			(size 0 0)
			(layers "F.Cu" "F.Mask" "F.Paste")
			(net "PWRGD_P12V_SSD15_R")
		)
	)
	(footprint ""
		(layer "F.Cu")
		(at 219.39123 -86.475316)
		(property "Reference" "C2809"
			(at 0 0 0)
			(layer "F.SilkS")
			(hide yes)
			(effects
				(font
					(size 1.27 1.27)
				)
			)
		)
		(property "Value" ""
			(at 0 0 0)
			(layer "F.Fab")
			(effects
				(font
					(size 1.27 1.27)
				)
			)
		)
		(duplicate_pad_numbers_are_jumpers no)
		(fp_line
			(start -0.7874 -0.4064)
			(end 0.7874 -0.4064)
			(stroke
				(width 0.1524)
				(type default)
			)
			(layer "F.SilkS")
		)
		(fp_line
			(start -0.7874 0.4064)
			(end -0.7874 -0.4064)
			(stroke
				(width 0.1524)
				(type default)
			)
			(layer "F.SilkS")
		)
		(fp_line
			(start 0.7874 -0.4064)
			(end 0.7874 0.4064)
			(stroke
				(width 0.1524)
				(type default)
			)
			(layer "F.SilkS")
		)
		(fp_line
			(start 0.7874 0.4064)
			(end -0.7874 0.4064)
			(stroke
				(width 0.1524)
				(type default)
			)
			(layer "F.SilkS")
		)
		(fp_line
			(start -0.67945 -0.305054)
			(end -0.12065 -0.305054)
			(stroke
				(width 0.1)
				(type default)
			)
			(layer "F.Fab")
		)
		(fp_line
			(start -0.67945 0.3048)
			(end -0.67945 -0.305054)
			(stroke
				(width 0.1)
				(type default)
			)
			(layer "F.Fab")
		)
		(fp_line
			(start -0.12065 -0.305054)
			(end -0.12065 -0.2794)
			(stroke
				(width 0.1)
				(type default)
			)
			(layer "F.Fab")
		)
		(fp_line
			(start -0.12065 -0.2794)
			(end 0.12065 -0.2794)
			(stroke
				(width 0.1)
				(type default)
			)
			(layer "F.Fab")
		)
		(fp_line
			(start -0.12065 0.2794)
			(end -0.12065 0.3048)
			(stroke
				(width 0.1)
				(type default)
			)
			(layer "F.Fab")
		)
		(fp_line
			(start -0.12065 0.3048)
			(end -0.67945 0.3048)
			(stroke
				(width 0.1)
				(type default)
			)
			(layer "F.Fab")
		)
		(fp_line
			(start 0.120396 0.2794)
			(end -0.12065 0.2794)
			(stroke
				(width 0.1)
				(type default)
			)
			(layer "F.Fab")
		)
		(fp_line
			(start 0.120396 0.3048)
			(end 0.120396 0.2794)
			(stroke
				(width 0.1)
				(type default)
			)
			(layer "F.Fab")
		)
		(fp_line
			(start 0.12065 -0.3048)
			(end 0.67945 -0.3048)
			(stroke
				(width 0.1)
				(type default)
			)
			(layer "F.Fab")
		)
		(fp_line
			(start 0.12065 -0.2794)
			(end 0.12065 -0.3048)
			(stroke
				(width 0.1)
				(type default)
			)
			(layer "F.Fab")
		)
		(fp_line
			(start 0.67945 -0.3048)
			(end 0.67945 0.3048)
			(stroke
				(width 0.1)
				(type default)
			)
			(layer "F.Fab")
		)
		(fp_line
			(start 0.67945 0.3048)
			(end 0.120396 0.3048)
			(stroke
				(width 0.1)
				(type default)
			)
			(layer "F.Fab")
		)
		(pad "1" smd circle
			(at -0.40005 0)
			(size 0 0)
			(layers "F.Cu" "F.Mask" "F.Paste")
			(net "P3V3_AUX")
		)
		(pad "2" smd circle
			(at 0.40005 0)
			(size 0 0)
			(layers "F.Cu" "F.Mask" "F.Paste")
			(net "GND")
		)
	)
)
